(kicad_pcb
	(version 20260206)
	(generator "pcbnew")
	(generator_version "10.0")
	(general
		(thickness 1.6)
		(legacy_teardrops no)
	)
	(paper "A4")
	(title_block
		(title "panther-plus-userver — 13130-1b_20150205.brd")
		(comment 1 "Honey Badger (Wiwynn) / footprints 1379-1386 of 1509")
	)
	(layers
		(0 "F.Cu" signal "TOP")
		(4 "In1.Cu" signal "L2")
		(6 "In2.Cu" signal "L3")
		(8 "In3.Cu" signal "L4")
		(10 "In4.Cu" signal "L5")
		(12 "In5.Cu" signal "L6")
		(14 "In6.Cu" signal "L7")
		(16 "In7.Cu" signal "L8")
		(18 "In8.Cu" signal "L9")
		(20 "In9.Cu" signal "L10")
		(22 "In10.Cu" signal "L11")
		(2 "B.Cu" signal "BOTTOM")
		(9 "F.Adhes" user "F.Adhesive")
		(11 "B.Adhes" user "B.Adhesive")
		(13 "F.Paste" user "Package Geometry/Pastemask Top")
		(15 "B.Paste" user "Package Geometry/Pastemask Bottom")
		(5 "F.SilkS" user "Ref Des/Silkscreen Top")
		(7 "B.SilkS" user "Ref Des/Silkscreen Bottom")
		(1 "F.Mask" user "Board Geometry/Soldermask Top")
		(3 "B.Mask" user "Board Geometry/Soldermask Bottom")
		(17 "Dwgs.User" user "User.Drawings")
		(19 "Cmts.User" user "User.Comments")
		(21 "Eco1.User" user "User.Eco1")
		(23 "Eco2.User" user "User.Eco2")
		(25 "Edge.Cuts" user "Board Geometry/Outline")
		(27 "Margin" user)
		(31 "F.CrtYd" user "Package Geometry/Place Bound Top")
		(29 "B.CrtYd" user "Package Geometry/Place Bound Bottom")
		(35 "F.Fab" user "Ref Des/Assembly Top")
		(33 "B.Fab" user "Ref Des/Assembly Bottom")
	)
	(footprint ""
		(layer "B.Cu")
		(at 38.227 -45.339 180)
		(property "Reference" "C66"
			(at 0 0 0)
			(layer "B.SilkS")
			(hide yes)
			(effects
				(font
					(size 1.27 1.27)
				)
				(justify mirror)
			)
		)
		(property "Value" "SC27P50V2GN-GP"
			(at -1.8923 -1.2065 180)
			(unlocked yes)
			(layer "B.Fab")
			(hide yes)
			(effects
				(font
					(size 1.016 1.016)
					(thickness 0.1524)
				)
				(justify mirror)
			)
		)
		(property "Device Type" "C402H22"
			(at -1.8923 -2.7305 180)
			(unlocked yes)
			(layer "B.Fab")
			(hide yes)
			(effects
				(font
					(size 1.016 1.016)
					(thickness 0.1524)
				)
				(justify mirror)
			)
		)
		(duplicate_pad_numbers_are_jumpers no)
		(fp_rect
			(start 0.381 0.7366)
			(end -0.381 -0.7366)
			(stroke
				(width 0)
				(type default)
			)
			(fill no)
			(layer "B.CrtYd")
		)
		(fp_rect
			(start 0.381 0.7366)
			(end -0.381 -0.7366)
			(stroke
				(width 0)
				(type default)
			)
			(fill no)
			(layer "B.Fab")
		)
		(pad "1" smd custom
			(at 0 -0.4572)
			(size 0.1143 0.1143)
			(layers "B.Cu" "B.Mask" "B.Paste")
			(net "XTAL_CLK_GEN_IN")
			(options
				(clearance outline)
				(anchor circle)
			)
			(primitives
				(gr_poly
					(pts
						(arc
							(start -0.254 0.1778)
							(mid -0.239121 0.213721)
							(end -0.2032 0.2286)
						)
						(arc
							(start 0.2032 0.2286)
							(mid 0.239121 0.213721)
							(end 0.254 0.1778)
						)
						(arc
							(start 0.254 -0.1778)
							(mid 0.239121 -0.213721)
							(end 0.2032 -0.2286)
						)
						(arc
							(start -0.2032 -0.2286)
							(mid -0.239121 -0.213721)
							(end -0.254 -0.1778)
						)
					)
					(width 0)
					(fill yes)
				)
			)
		)
		(pad "2" smd custom
			(at 0 0.4572)
			(size 0.1143 0.1143)
			(layers "B.Cu" "B.Mask" "B.Paste")
			(net "GND")
			(options
				(clearance outline)
				(anchor circle)
			)
			(primitives
				(gr_poly
					(pts
						(arc
							(start -0.254 0.1778)
							(mid -0.239121 0.213721)
							(end -0.2032 0.2286)
						)
						(arc
							(start 0.2032 0.2286)
							(mid 0.239121 0.213721)
							(end 0.254 0.1778)
						)
						(arc
							(start 0.254 -0.1778)
							(mid 0.239121 -0.213721)
							(end 0.2032 -0.2286)
						)
						(arc
							(start -0.2032 -0.2286)
							(mid -0.239121 -0.213721)
							(end -0.254 -0.1778)
						)
					)
					(width 0)
					(fill yes)
				)
			)
		)
	)
	(footprint ""
		(layer "B.Cu")
		(at 130.429 -32.004 90)
		(property "Reference" "C139"
			(at 0 0 90)
			(layer "B.SilkS")
			(hide yes)
			(effects
				(font
					(size 1.27 1.27)
				)
				(justify mirror)
			)
		)
		(property "Value" "SCD1U10V2KX-5GP"
			(at -1.1811 -2.7051 90)
			(unlocked yes)
			(layer "B.Fab")
			(hide yes)
			(effects
				(font
					(size 1.016 1.016)
					(thickness 0.1524)
				)
				(justify mirror)
			)
		)
		(property "Device Type" "C402H22"
			(at -1.1811 -4.2291 90)
			(unlocked yes)
			(layer "B.Fab")
			(hide yes)
			(effects
				(font
					(size 1.016 1.016)
					(thickness 0.1524)
				)
				(justify mirror)
			)
		)
		(duplicate_pad_numbers_are_jumpers no)
		(fp_rect
			(start 0.381 0.7366)
			(end -0.381 -0.7366)
			(stroke
				(width 0)
				(type default)
			)
			(fill no)
			(layer "B.CrtYd")
		)
		(fp_rect
			(start 0.381 0.7366)
			(end -0.381 -0.7366)
			(stroke
				(width 0)
				(type default)
			)
			(fill no)
			(layer "B.Fab")
		)
		(pad "1" smd custom
			(at 0 -0.4572 270)
			(size 0.1143 0.1143)
			(layers "B.Cu" "B.Mask" "B.Paste")
			(net "P3V3_STBY")
			(options
				(clearance outline)
				(anchor circle)
			)
			(primitives
				(gr_poly
					(pts
						(arc
							(start -0.254 0.1778)
							(mid -0.239121 0.213721)
							(end -0.2032 0.2286)
						)
						(arc
							(start 0.2032 0.2286)
							(mid 0.239121 0.213721)
							(end 0.254 0.1778)
						)
						(arc
							(start 0.254 -0.1778)
							(mid 0.239121 -0.213721)
							(end 0.2032 -0.2286)
						)
						(arc
							(start -0.2032 -0.2286)
							(mid -0.239121 -0.213721)
							(end -0.254 -0.1778)
						)
					)
					(width 0)
					(fill yes)
				)
			)
		)
		(pad "2" smd custom
			(at 0 0.4572 270)
			(size 0.1143 0.1143)
			(layers "B.Cu" "B.Mask" "B.Paste")
			(net "GND")
			(options
				(clearance outline)
				(anchor circle)
			)
			(primitives
				(gr_poly
					(pts
						(arc
							(start -0.254 0.1778)
							(mid -0.239121 0.213721)
							(end -0.2032 0.2286)
						)
						(arc
							(start 0.2032 0.2286)
							(mid 0.239121 0.213721)
							(end 0.254 0.1778)
						)
						(arc
							(start 0.254 -0.1778)
							(mid 0.239121 -0.213721)
							(end 0.2032 -0.2286)
						)
						(arc
							(start -0.2032 -0.2286)
							(mid -0.239121 -0.213721)
							(end -0.254 -0.1778)
						)
					)
					(width 0)
					(fill yes)
				)
			)
		)
	)
	(footprint ""
		(layer "B.Cu")
		(at 76.835 -16.3576 -90)
		(property "Reference" "PC200"
			(at 0 0 90)
			(layer "B.SilkS")
			(hide yes)
			(effects
				(font
					(size 1.27 1.27)
				)
				(justify mirror)
			)
		)
		(property "Value" "SC10U6D3V5KX-4GP"
			(at 0.0762 -6.1214 270)
			(unlocked yes)
			(layer "B.Fab")
			(hide yes)
			(effects
				(font
					(size 1.016 1.016)
					(thickness 0.1524)
				)
				(justify mirror)
			)
		)
		(property "Device Type" "C805H58"
			(at 0.0762 -8.1534 270)
			(unlocked yes)
			(layer "B.Fab")
			(hide yes)
			(effects
				(font
					(size 1.016 1.016)
					(thickness 0.1524)
				)
				(justify mirror)
			)
		)
		(duplicate_pad_numbers_are_jumpers no)
		(fp_line
			(start -0.6096 0)
			(end 0.6096 0)
			(stroke
				(width 0.3048)
				(type default)
			)
			(layer "B.SilkS")
		)
		(fp_poly
			(pts
				(xy 0.9017 1.4351) (xy -0.9017 1.4351) (xy -0.9017 -1.4351) (xy 0.9017 -1.4351)
			)
			(stroke
				(width 0)
				(type default)
			)
			(fill no)
			(layer "B.CrtYd")
		)
		(fp_poly
			(pts
				(xy -0.9017 1.4351) (xy -0.9017 -1.4351) (xy 0.9017 -1.4351) (xy 0.9017 1.4351)
			)
			(stroke
				(width 0)
				(type default)
			)
			(fill no)
			(layer "B.Fab")
		)
		(pad "1" smd rect
			(at 0 -0.8382 90)
			(size 1.5494 0.9398)
			(layers "B.Cu" "B.Mask" "B.Paste")
			(net "TPS74801_P1V35_IN")
		)
		(pad "2" smd rect
			(at 0 0.8382 90)
			(size 1.5494 0.9398)
			(layers "B.Cu" "B.Mask" "B.Paste")
			(net "GND")
		)
	)
	(footprint ""
		(layer "B.Cu")
		(at 27.686 -32.385 180)
		(property "Reference" "PC42"
			(at 0 0 0)
			(layer "B.SilkS")
			(hide yes)
			(effects
				(font
					(size 1.27 1.27)
				)
				(justify mirror)
			)
		)
		(property "Value" "SC22U6D3V3MX-1-GP"
			(at 0.0254 -2.0193 180)
			(unlocked yes)
			(layer "B.Fab")
			(hide yes)
			(effects
				(font
					(size 1.016 1.016)
					(thickness 0.1524)
				)
				(justify mirror)
			)
		)
		(property "Device Type" "C603H40"
			(at 0.0254 -3.5433 180)
			(unlocked yes)
			(layer "B.Fab")
			(hide yes)
			(effects
				(font
					(size 1.016 1.016)
					(thickness 0.1524)
				)
				(justify mirror)
			)
		)
		(duplicate_pad_numbers_are_jumpers no)
		(fp_line
			(start 0.4064 0)
			(end -0.4064 0)
			(stroke
				(width 0.2286)
				(type default)
			)
			(layer "B.SilkS")
		)
		(fp_rect
			(start 0.635 1.1811)
			(end -0.635 -1.1811)
			(stroke
				(width 0)
				(type default)
			)
			(fill no)
			(layer "B.CrtYd")
		)
		(fp_rect
			(start 0.635 1.1811)
			(end -0.635 -1.1811)
			(stroke
				(width 0)
				(type default)
			)
			(fill no)
			(layer "B.Fab")
		)
		(pad "1" smd custom
			(at 0 -0.6604)
			(size 0.19685 0.19685)
			(layers "B.Cu" "B.Mask" "B.Paste")
			(net "P1V0")
			(options
				(clearance outline)
				(anchor circle)
			)
			(primitives
				(gr_poly
					(pts
						(arc
							(start 0.508 0.2921)
							(mid 0.478242 0.363942)
							(end 0.4064 0.3937)
						)
						(arc
							(start -0.4064 0.3937)
							(mid -0.478242 0.363942)
							(end -0.508 0.2921)
						)
						(arc
							(start -0.508 -0.2921)
							(mid -0.478242 -0.363942)
							(end -0.4064 -0.3937)
						)
						(arc
							(start 0.4064 -0.3937)
							(mid 0.478242 -0.363942)
							(end 0.508 -0.2921)
						)
					)
					(width 0)
					(fill yes)
				)
			)
		)
		(pad "2" smd custom
			(at 0 0.6604)
			(size 0.19685 0.19685)
			(layers "B.Cu" "B.Mask" "B.Paste")
			(net "GND")
			(options
				(clearance outline)
				(anchor circle)
			)
			(primitives
				(gr_poly
					(pts
						(arc
							(start 0.508 0.2921)
							(mid 0.478242 0.363942)
							(end 0.4064 0.3937)
						)
						(arc
							(start -0.4064 0.3937)
							(mid -0.478242 0.363942)
							(end -0.508 0.2921)
						)
						(arc
							(start -0.508 -0.2921)
							(mid -0.478242 -0.363942)
							(end -0.4064 -0.3937)
						)
						(arc
							(start 0.4064 -0.3937)
							(mid 0.478242 -0.363942)
							(end 0.508 -0.2921)
						)
					)
					(width 0)
					(fill yes)
				)
			)
		)
	)
	(footprint ""
		(layer "B.Cu")
		(at 129.54 -59.944)
		(property "Reference" "R228"
			(at 0 0 0)
			(layer "B.SilkS")
			(hide yes)
			(effects
				(font
					(size 1.27 1.27)
				)
				(justify mirror)
			)
		)
		(property "Value" "4K7R2F-GP"
			(at -0.064008 -3.993896 0)
			(unlocked yes)
			(layer "B.Fab")
			(hide yes)
			(effects
				(font
					(size 1.016 1.016)
					(thickness 0.1524)
				)
				(justify mirror)
			)
		)
		(property "Device Type" "R402H16"
			(at -0.064008 -5.517896 0)
			(unlocked yes)
			(layer "B.Fab")
			(hide yes)
			(effects
				(font
					(size 1.016 1.016)
					(thickness 0.1524)
				)
				(justify mirror)
			)
		)
		(duplicate_pad_numbers_are_jumpers no)
		(fp_rect
			(start 0.381 0.8382)
			(end -0.381 -0.8382)
			(stroke
				(width 0)
				(type default)
			)
			(fill no)
			(layer "B.CrtYd")
		)
		(fp_rect
			(start 0.381 0.8382)
			(end -0.381 -0.8382)
			(stroke
				(width 0)
				(type default)
			)
			(fill no)
			(layer "B.Fab")
		)
		(pad "1" smd custom
			(at 0 -0.4318 180)
			(size 0.127 0.127)
			(layers "B.Cu" "B.Mask" "B.Paste")
			(net "CHA_0_SA1")
			(options
				(clearance outline)
				(anchor circle)
			)
			(primitives
				(gr_poly
					(pts
						(arc
							(start -0.2032 0.2794)
							(mid -0.239121 0.264521)
							(end -0.254 0.2286)
						)
						(arc
							(start -0.254 -0.2286)
							(mid -0.239121 -0.264521)
							(end -0.2032 -0.2794)
						)
						(arc
							(start 0.2032 -0.2794)
							(mid 0.239121 -0.264521)
							(end 0.254 -0.2286)
						)
						(arc
							(start 0.254 0.2286)
							(mid 0.239121 0.264521)
							(end 0.2032 0.2794)
						)
					)
					(width 0)
					(fill yes)
				)
			)
		)
		(pad "2" smd custom
			(at 0 0.4318 180)
			(size 0.127 0.127)
			(layers "B.Cu" "B.Mask" "B.Paste")
			(net "GND")
			(options
				(clearance outline)
				(anchor circle)
			)
			(primitives
				(gr_poly
					(pts
						(arc
							(start -0.2032 0.2794)
							(mid -0.239121 0.264521)
							(end -0.254 0.2286)
						)
						(arc
							(start -0.254 -0.2286)
							(mid -0.239121 -0.264521)
							(end -0.2032 -0.2794)
						)
						(arc
							(start 0.2032 -0.2794)
							(mid 0.239121 -0.264521)
							(end 0.254 -0.2286)
						)
						(arc
							(start 0.254 0.2286)
							(mid 0.239121 0.264521)
							(end 0.2032 0.2794)
						)
					)
					(width 0)
					(fill yes)
				)
			)
		)
	)
	(footprint ""
		(layer "B.Cu")
		(at 36.957 -49.403 90)
		(property "Reference" "R137"
			(at 0 0 90)
			(layer "B.SilkS")
			(hide yes)
			(effects
				(font
					(size 1.27 1.27)
				)
				(justify mirror)
			)
		)
		(property "Value" "10KR2F-2-GP"
			(at -1.7907 -1.1176 90)
			(unlocked yes)
			(layer "B.Fab")
			(hide yes)
			(effects
				(font
					(size 1.016 1.016)
					(thickness 0.1524)
				)
				(justify mirror)
			)
		)
		(property "Device Type" "R402H16"
			(at -1.7907 -2.6416 90)
			(unlocked yes)
			(layer "B.Fab")
			(hide yes)
			(effects
				(font
					(size 1.016 1.016)
					(thickness 0.1524)
				)
				(justify mirror)
			)
		)
		(duplicate_pad_numbers_are_jumpers no)
		(fp_rect
			(start 0.381 0.8382)
			(end -0.381 -0.8382)
			(stroke
				(width 0)
				(type default)
			)
			(fill no)
			(layer "B.CrtYd")
		)
		(fp_rect
			(start 0.381 0.8382)
			(end -0.381 -0.8382)
			(stroke
				(width 0)
				(type default)
			)
			(fill no)
			(layer "B.Fab")
		)
		(pad "1" smd custom
			(at 0 -0.4318 270)
			(size 0.127 0.127)
			(layers "B.Cu" "B.Mask" "B.Paste")
			(net "P3V3_STBY")
			(options
				(clearance outline)
				(anchor circle)
			)
			(primitives
				(gr_poly
					(pts
						(arc
							(start -0.2032 0.2794)
							(mid -0.239121 0.264521)
							(end -0.254 0.2286)
						)
						(arc
							(start -0.254 -0.2286)
							(mid -0.239121 -0.264521)
							(end -0.2032 -0.2794)
						)
						(arc
							(start 0.2032 -0.2794)
							(mid 0.239121 -0.264521)
							(end 0.254 -0.2286)
						)
						(arc
							(start 0.254 0.2286)
							(mid 0.239121 0.264521)
							(end 0.2032 0.2794)
						)
					)
					(width 0)
					(fill yes)
				)
			)
		)
		(pad "2" smd custom
			(at 0 0.4318 270)
			(size 0.127 0.127)
			(layers "B.Cu" "B.Mask" "B.Paste")
			(net "CLK_14M_CPU")
			(options
				(clearance outline)
				(anchor circle)
			)
			(primitives
				(gr_poly
					(pts
						(arc
							(start -0.2032 0.2794)
							(mid -0.239121 0.264521)
							(end -0.254 0.2286)
						)
						(arc
							(start -0.254 -0.2286)
							(mid -0.239121 -0.264521)
							(end -0.2032 -0.2794)
						)
						(arc
							(start 0.2032 -0.2794)
							(mid 0.239121 -0.264521)
							(end 0.254 -0.2286)
						)
						(arc
							(start 0.254 0.2286)
							(mid 0.239121 0.264521)
							(end 0.2032 0.2794)
						)
					)
					(width 0)
					(fill yes)
				)
			)
		)
	)
	(footprint ""
		(layer "B.Cu")
		(at 82.5754 -27.4828 180)
		(property "Reference" "R406"
			(at 0 0 0)
			(layer "B.SilkS")
			(hide yes)
			(effects
				(font
					(size 1.27 1.27)
				)
				(justify mirror)
			)
		)
		(property "Value" "1KR2F-3-GP"
			(at -1.7907 -1.1176 180)
			(unlocked yes)
			(layer "B.Fab")
			(hide yes)
			(effects
				(font
					(size 1.016 1.016)
					(thickness 0.1524)
				)
				(justify mirror)
			)
		)
		(property "Device Type" "R402H16"
			(at -1.7907 -2.6416 180)
			(unlocked yes)
			(layer "B.Fab")
			(hide yes)
			(effects
				(font
					(size 1.016 1.016)
					(thickness 0.1524)
				)
				(justify mirror)
			)
		)
		(duplicate_pad_numbers_are_jumpers no)
		(fp_rect
			(start 0.381 0.8382)
			(end -0.381 -0.8382)
			(stroke
				(width 0)
				(type default)
			)
			(fill no)
			(layer "B.CrtYd")
		)
		(fp_rect
			(start 0.381 0.8382)
			(end -0.381 -0.8382)
			(stroke
				(width 0)
				(type default)
			)
			(fill no)
			(layer "B.Fab")
		)
		(pad "1" smd custom
			(at 0 -0.4318)
			(size 0.127 0.127)
			(layers "B.Cu" "B.Mask" "B.Paste")
			(net "BD_REV_2")
			(options
				(clearance outline)
				(anchor circle)
			)
			(primitives
				(gr_poly
					(pts
						(arc
							(start -0.2032 0.2794)
							(mid -0.239121 0.264521)
							(end -0.254 0.2286)
						)
						(arc
							(start -0.254 -0.2286)
							(mid -0.239121 -0.264521)
							(end -0.2032 -0.2794)
						)
						(arc
							(start 0.2032 -0.2794)
							(mid 0.239121 -0.264521)
							(end 0.254 -0.2286)
						)
						(arc
							(start 0.254 0.2286)
							(mid 0.239121 0.264521)
							(end 0.2032 0.2794)
						)
					)
					(width 0)
					(fill yes)
				)
			)
		)
		(pad "2" smd custom
			(at 0 0.4318)
			(size 0.127 0.127)
			(layers "B.Cu" "B.Mask" "B.Paste")
			(net "GND")
			(options
				(clearance outline)
				(anchor circle)
			)
			(primitives
				(gr_poly
					(pts
						(arc
							(start -0.2032 0.2794)
							(mid -0.239121 0.264521)
							(end -0.254 0.2286)
						)
						(arc
							(start -0.254 -0.2286)
							(mid -0.239121 -0.264521)
							(end -0.2032 -0.2794)
						)
						(arc
							(start 0.2032 -0.2794)
							(mid 0.239121 -0.264521)
							(end 0.254 -0.2286)
						)
						(arc
							(start 0.254 0.2286)
							(mid 0.239121 0.264521)
							(end 0.2032 0.2794)
						)
					)
					(width 0)
					(fill yes)
				)
			)
		)
	)
	(footprint ""
		(layer "B.Cu")
		(at 53.467 -18.034 -90)
		(property "Reference" "C302"
			(at 0 0 90)
			(layer "B.SilkS")
			(hide yes)
			(effects
				(font
					(size 1.27 1.27)
				)
				(justify mirror)
			)
		)
		(property "Value" "SC1U6D3V2KX-GP"
			(at -1.8923 -1.2065 270)
			(unlocked yes)
			(layer "B.Fab")
			(hide yes)
			(effects
				(font
					(size 1.016 1.016)
					(thickness 0.1524)
				)
				(justify mirror)
			)
		)
		(property "Device Type" "C402H22"
			(at -1.8923 -2.7305 270)
			(unlocked yes)
			(layer "B.Fab")
			(hide yes)
			(effects
				(font
					(size 1.016 1.016)
					(thickness 0.1524)
				)
				(justify mirror)
			)
		)
		(duplicate_pad_numbers_are_jumpers no)
		(fp_rect
			(start 0.381 0.7366)
			(end -0.381 -0.7366)
			(stroke
				(width 0)
				(type default)
			)
			(fill no)
			(layer "B.CrtYd")
		)
		(fp_rect
			(start 0.381 0.7366)
			(end -0.381 -0.7366)
			(stroke
				(width 0)
				(type default)
			)
			(fill no)
			(layer "B.Fab")
		)
		(pad "1" smd custom
			(at 0 -0.4572 90)
			(size 0.1143 0.1143)
			(layers "B.Cu" "B.Mask" "B.Paste")
			(net "P3V3")
			(options
				(clearance outline)
				(anchor circle)
			)
			(primitives
				(gr_poly
					(pts
						(arc
							(start -0.254 0.1778)
							(mid -0.239121 0.213721)
							(end -0.2032 0.2286)
						)
						(arc
							(start 0.2032 0.2286)
							(mid 0.239121 0.213721)
							(end 0.254 0.1778)
						)
						(arc
							(start 0.254 -0.1778)
							(mid 0.239121 -0.213721)
							(end 0.2032 -0.2286)
						)
						(arc
							(start -0.2032 -0.2286)
							(mid -0.239121 -0.213721)
							(end -0.254 -0.1778)
						)
					)
					(width 0)
					(fill yes)
				)
			)
		)
		(pad "2" smd custom
			(at 0 0.4572 90)
			(size 0.1143 0.1143)
			(layers "B.Cu" "B.Mask" "B.Paste")
			(net "GND")
			(options
				(clearance outline)
				(anchor circle)
			)
			(primitives
				(gr_poly
					(pts
						(arc
							(start -0.254 0.1778)
							(mid -0.239121 0.213721)
							(end -0.2032 0.2286)
						)
						(arc
							(start 0.2032 0.2286)
							(mid 0.239121 0.213721)
							(end 0.254 0.1778)
						)
						(arc
							(start 0.254 -0.1778)
							(mid 0.239121 -0.213721)
							(end 0.2032 -0.2286)
						)
						(arc
							(start -0.2032 -0.2286)
							(mid -0.239121 -0.213721)
							(end -0.254 -0.1778)
						)
					)
					(width 0)
					(fill yes)
				)
			)
		)
	)
)
